(kicad_pcb
	(version 20260206)
	(generator "pcbnew")
	(generator_version "10.0")
	(general
		(thickness 1.6)
		(legacy_teardrops no)
	)
	(paper "A4")
	(title_block
		(title "Wiwynn_Tioga_Pass_MB.brd")
		(comment 1 "Tioga Pass / footprints 1523-1528 of 4770")
	)
	(layers
		(0 "F.Cu" signal "TOP")
		(4 "In1.Cu" signal "L2GND")
		(6 "In2.Cu" signal "L3")
		(8 "In3.Cu" signal "L4GND")
		(10 "In4.Cu" signal "L5")
		(12 "In5.Cu" signal "L6GND")
		(14 "In6.Cu" signal "L7VCC")
		(16 "In7.Cu" signal "L8VCC")
		(18 "In8.Cu" signal "L9GND")
		(20 "In9.Cu" signal "L10")
		(22 "In10.Cu" signal "L11GND")
		(24 "In11.Cu" signal "L12")
		(26 "In12.Cu" signal "L13GND")
		(2 "B.Cu" signal "BOTTOM")
		(9 "F.Adhes" user "F.Adhesive")
		(11 "B.Adhes" user "B.Adhesive")
		(13 "F.Paste" user "Package Geometry/Pastemask Top")
		(15 "B.Paste" user "Package Geometry/Pastemask Bottom")
		(5 "F.SilkS" user "Ref Des/Silkscreen Top")
		(7 "B.SilkS" user "Ref Des/Silkscreen Bottom")
		(1 "F.Mask" user "Board Geometry/Soldermask Top")
		(3 "B.Mask" user "Board Geometry/Soldermask Bottom")
		(17 "Dwgs.User" user "User.Drawings")
		(19 "Cmts.User" user "User.Comments")
		(21 "Eco1.User" user "User.Eco1")
		(23 "Eco2.User" user "User.Eco2")
		(25 "Edge.Cuts" user "Board Geometry/Outline")
		(27 "Margin" user)
		(31 "F.CrtYd" user "Package Geometry/Place Bound Top")
		(29 "B.CrtYd" user "Package Geometry/Place Bound Bottom")
		(35 "F.Fab" user "Ref Des/Assembly Top")
		(33 "B.Fab" user "Ref Des/Assembly Bottom")
	)
	(footprint ""
		(layer "F.Cu")
		(at 348.053914 -149.939502 -90)
		(property "Reference" "C7A5"
			(at 0 0 270)
			(layer "F.SilkS")
			(hide yes)
			(effects
				(font
					(size 1.27 1.27)
				)
			)
		)
		(property "Value" ""
			(at 0 0 270)
			(layer "F.Fab")
			(effects
				(font
					(size 1.27 1.27)
				)
			)
		)
		(duplicate_pad_numbers_are_jumpers no)
		(fp_poly
			(pts
				(xy 0.3048 -0.1016) (xy 0.3048 0.9906) (xy -0.3048 0.9906) (xy -0.3048 -0.1016)
			)
			(stroke
				(width 0)
				(type default)
			)
			(fill no)
			(layer "F.CrtYd")
		)
		(fp_line
			(start -0.3048 0.9906)
			(end 0.3048 0.9906)
			(stroke
				(width 0.1)
				(type default)
			)
			(layer "F.Fab")
		)
		(fp_line
			(start 0.3048 0.9906)
			(end 0.3048 -0.1016)
			(stroke
				(width 0.1)
				(type default)
			)
			(layer "F.Fab")
		)
		(fp_line
			(start -0.3048 -0.1016)
			(end -0.3048 0.9906)
			(stroke
				(width 0.1)
				(type default)
			)
			(layer "F.Fab")
		)
		(fp_line
			(start 0.3048 -0.1016)
			(end -0.3048 -0.1016)
			(stroke
				(width 0.1)
				(type default)
			)
			(layer "F.Fab")
		)
		(pad "1" smd rect
			(at 0 0 270)
			(size 0.508 0.508)
			(layers "F.Cu" "F.Mask" "F.Paste")
			(net "VR_FET_SW_P12V_STBY_PVDDQ_DEF")
		)
		(pad "2" smd rect
			(at 0 0.889 270)
			(size 0.508 0.508)
			(layers "F.Cu" "F.Mask" "F.Paste")
			(net "GND")
		)
		(zone
			(layer "F.Cu")
			(hatch none 0.5)
			(connect_pads
				(clearance 0)
			)
			(min_thickness 0.25)
			(keepout
				(tracks not_allowed)
				(vias allowed)
				(pads allowed)
				(copperpour not_allowed)
				(footprints allowed)
			)
			(placement
				(enabled no)
				(sheetname "")
			)
			(fill
				(thermal_gap 0.5)
				(thermal_bridge_width 0.5)
				(island_removal_mode 0)
			)
			(polygon
				(pts
					(xy 347.418914 -150.193502) (xy 347.418914 -149.685502) (xy 347.799914 -149.685502) (xy 347.799914 -150.193502)
				)
			)
		)
		(zone
			(layer "F.Cu")
			(hatch none 0.5)
			(connect_pads
				(clearance 0)
			)
			(min_thickness 0.25)
			(keepout
				(tracks allowed)
				(vias not_allowed)
				(pads allowed)
				(copperpour not_allowed)
				(footprints allowed)
			)
			(placement
				(enabled no)
				(sheetname "")
			)
			(fill
				(thermal_gap 0.5)
				(thermal_bridge_width 0.5)
				(island_removal_mode 0)
			)
			(polygon
				(pts
					(xy 347.799914 -150.193502) (xy 347.799914 -149.685502) (xy 347.418914 -149.685502) (xy 347.418914 -150.193502)
				)
			)
		)
	)
	(footprint ""
		(layer "F.Cu")
		(at 340.806278 -24.508206 90)
		(property "Reference" "R7F9"
			(at 0 0 90)
			(layer "F.SilkS")
			(hide yes)
			(effects
				(font
					(size 1.27 1.27)
				)
			)
		)
		(property "Value" ""
			(at 0 0 90)
			(layer "F.Fab")
			(effects
				(font
					(size 1.27 1.27)
				)
			)
		)
		(duplicate_pad_numbers_are_jumpers no)
		(fp_poly
			(pts
				(xy -0.2794 -0.1016) (xy 0.2794 -0.1016) (xy 0.2794 0.9906) (xy -0.2794 0.9906)
			)
			(stroke
				(width 0)
				(type default)
			)
			(fill no)
			(layer "F.CrtYd")
		)
		(fp_line
			(start 0.2794 -0.1016)
			(end -0.2794 -0.1016)
			(stroke
				(width 0.1)
				(type default)
			)
			(layer "F.Fab")
		)
		(fp_line
			(start -0.2794 -0.1016)
			(end -0.2794 0.9906)
			(stroke
				(width 0.1)
				(type default)
			)
			(layer "F.Fab")
		)
		(fp_line
			(start 0.2794 0.9906)
			(end 0.2794 -0.1016)
			(stroke
				(width 0.1)
				(type default)
			)
			(layer "F.Fab")
		)
		(fp_line
			(start -0.2794 0.9906)
			(end 0.2794 0.9906)
			(stroke
				(width 0.1)
				(type default)
			)
			(layer "F.Fab")
		)
		(pad "1" smd rect
			(at 0 0 90)
			(size 0.508 0.508)
			(layers "F.Cu" "F.Mask" "F.Paste")
			(net "FM_PVPP_CPU0_EN")
		)
		(pad "2" smd rect
			(at 0 0.889 90)
			(size 0.508 0.508)
			(layers "F.Cu" "F.Mask" "F.Paste")
			(net "FM_PVPP_PVDDQ_CPU0_EN_ABC")
		)
		(zone
			(layer "F.Cu")
			(hatch none 0.5)
			(connect_pads
				(clearance 0)
			)
			(min_thickness 0.25)
			(keepout
				(tracks allowed)
				(vias not_allowed)
				(pads allowed)
				(copperpour not_allowed)
				(footprints allowed)
			)
			(placement
				(enabled no)
				(sheetname "")
			)
			(fill
				(thermal_gap 0.5)
				(thermal_bridge_width 0.5)
				(island_removal_mode 0)
			)
			(polygon
				(pts
					(xy 341.060278 -24.254206) (xy 341.060278 -24.762206) (xy 341.441278 -24.762206) (xy 341.441278 -24.254206)
				)
			)
		)
		(zone
			(layer "F.Cu")
			(hatch none 0.5)
			(connect_pads
				(clearance 0)
			)
			(min_thickness 0.25)
			(keepout
				(tracks not_allowed)
				(vias allowed)
				(pads allowed)
				(copperpour not_allowed)
				(footprints allowed)
			)
			(placement
				(enabled no)
				(sheetname "")
			)
			(fill
				(thermal_gap 0.5)
				(thermal_bridge_width 0.5)
				(island_removal_mode 0)
			)
			(polygon
				(pts
					(xy 341.441278 -24.254206) (xy 341.441278 -24.762206) (xy 341.060278 -24.762206) (xy 341.060278 -24.254206)
				)
			)
		)
	)
	(footprint ""
		(layer "F.Cu")
		(at 193.127122 -140.177012 -90)
		(property "Reference" "C4A17"
			(at 0 0 270)
			(layer "F.SilkS")
			(hide yes)
			(effects
				(font
					(size 1.27 1.27)
				)
			)
		)
		(property "Value" ""
			(at 0 0 270)
			(layer "F.Fab")
			(effects
				(font
					(size 1.27 1.27)
				)
			)
		)
		(duplicate_pad_numbers_are_jumpers no)
		(fp_rect
			(start -0.7239 1.9939)
			(end 0.7239 -0.2159)
			(stroke
				(width 0)
				(type default)
			)
			(fill no)
			(layer "F.CrtYd")
		)
		(fp_line
			(start -0.7239 1.9939)
			(end 0.7239 1.9939)
			(stroke
				(width 0.1)
				(type default)
			)
			(layer "F.Fab")
		)
		(fp_line
			(start 0.7239 1.9939)
			(end 0.7239 -0.2159)
			(stroke
				(width 0.1)
				(type default)
			)
			(layer "F.Fab")
		)
		(fp_line
			(start -0.7239 -0.2159)
			(end -0.7239 1.9939)
			(stroke
				(width 0.1)
				(type default)
			)
			(layer "F.Fab")
		)
		(fp_line
			(start 0.7239 -0.2159)
			(end -0.7239 -0.2159)
			(stroke
				(width 0.1)
				(type default)
			)
			(layer "F.Fab")
		)
		(pad "1" smd rect
			(at 0 0 270)
			(size 1.27 1.016)
			(layers "F.Cu" "F.Mask" "F.Paste")
			(net "P12V_NVDIMM_DEF")
		)
		(pad "2" smd rect
			(at 0 1.778 270)
			(size 1.27 1.016)
			(layers "F.Cu" "F.Mask" "F.Paste")
			(net "GND")
		)
		(zone
			(layer "F.Cu")
			(hatch none 0.5)
			(connect_pads
				(clearance 0)
			)
			(min_thickness 0.25)
			(keepout
				(tracks not_allowed)
				(vias allowed)
				(pads allowed)
				(copperpour not_allowed)
				(footprints allowed)
			)
			(placement
				(enabled no)
				(sheetname "")
			)
			(fill
				(thermal_gap 0.5)
				(thermal_bridge_width 0.5)
				(island_removal_mode 0)
			)
			(polygon
				(pts
					(xy 191.857122 -140.812012) (xy 191.857122 -139.542012) (xy 192.619122 -139.542012) (xy 192.619122 -140.812012)
				)
			)
		)
	)
	(footprint ""
		(layer "F.Cu")
		(at 100.67544 -73.318116)
		(property "Reference" "C2D36"
			(at 0 0 0)
			(layer "F.SilkS")
			(hide yes)
			(effects
				(font
					(size 1.27 1.27)
				)
			)
		)
		(property "Value" ""
			(at 0 0 0)
			(layer "F.Fab")
			(effects
				(font
					(size 1.27 1.27)
				)
			)
		)
		(duplicate_pad_numbers_are_jumpers no)
		(fp_poly
			(pts
				(xy -0.4953 -0.2032) (xy 0.4953 -0.2032) (xy 0.4953 1.6002) (xy -0.4953 1.6002)
			)
			(stroke
				(width 0)
				(type default)
			)
			(fill no)
			(layer "F.CrtYd")
		)
		(fp_line
			(start -0.4953 -0.2032)
			(end 0.4953 -0.2032)
			(stroke
				(width 0.1)
				(type default)
			)
			(layer "F.Fab")
		)
		(fp_line
			(start -0.4953 1.6002)
			(end -0.4953 -0.2032)
			(stroke
				(width 0.1)
				(type default)
			)
			(layer "F.Fab")
		)
		(fp_line
			(start 0.4953 -0.2032)
			(end 0.4953 1.6002)
			(stroke
				(width 0.1)
				(type default)
			)
			(layer "F.Fab")
		)
		(fp_line
			(start 0.4953 1.6002)
			(end -0.4953 1.6002)
			(stroke
				(width 0.1)
				(type default)
			)
			(layer "F.Fab")
		)
		(pad "1" smd rect
			(at 0 0)
			(size 0.762 0.889)
			(layers "F.Cu" "F.Mask" "F.Paste")
			(net "PVCCIN_CPU1")
		)
		(pad "2" smd rect
			(at 0 1.397)
			(size 0.762 0.889)
			(layers "F.Cu" "F.Mask" "F.Paste")
			(net "GND")
		)
		(zone
			(layer "F.Cu")
			(hatch none 0.5)
			(connect_pads
				(clearance 0)
			)
			(min_thickness 0.25)
			(keepout
				(tracks not_allowed)
				(vias allowed)
				(pads allowed)
				(copperpour not_allowed)
				(footprints allowed)
			)
			(placement
				(enabled no)
				(sheetname "")
			)
			(fill
				(thermal_gap 0.5)
				(thermal_bridge_width 0.5)
				(island_removal_mode 0)
			)
			(polygon
				(pts
					(xy 100.29444 -72.873616) (xy 101.05644 -72.873616) (xy 101.05644 -72.365616) (xy 100.29444 -72.365616)
				)
			)
		)
	)
	(footprint ""
		(layer "F.Cu")
		(at 33.925002 -57.039764 90)
		(property "Reference" "EU1E2"
			(at 3.360166 -1.768602 0)
			(unlocked yes)
			(layer "F.SilkS")
			(effects
				(font
					(size 0.7874 0.5842)
					(thickness 0.1524)
				)
			)
		)
		(property "Value" ""
			(at 0 0 90)
			(layer "F.Fab")
			(effects
				(font
					(size 1.27 1.27)
				)
			)
		)
		(duplicate_pad_numbers_are_jumpers no)
		(fp_line
			(start 2.9718 -3.5052)
			(end 2.9718 3.429)
			(stroke
				(width 0.1524)
				(type default)
			)
			(layer "F.SilkS")
		)
		(fp_line
			(start -3.0099 -3.5052)
			(end 2.9718 -3.5052)
			(stroke
				(width 0.1524)
				(type default)
			)
			(layer "F.SilkS")
		)
		(fp_line
			(start 2.9718 3.429)
			(end -3.0099 3.429)
			(stroke
				(width 0.1524)
				(type default)
			)
			(layer "F.SilkS")
		)
		(fp_line
			(start -3.0099 3.429)
			(end -3.0099 -3.5052)
			(stroke
				(width 0.1524)
				(type default)
			)
			(layer "F.SilkS")
		)
		(fp_circle
			(center -3.057398 -2.678684)
			(end -3.057398 -2.551684)
			(stroke
				(width 0.254)
				(type default)
			)
			(fill no)
			(layer "F.SilkS")
		)
		(fp_poly
			(pts
				(xy -2.9972 -3.4925) (xy -2.9972 -2.6924) (xy -2.1971 -3.4925)
			)
			(stroke
				(width 0)
				(type default)
			)
			(fill yes)
			(layer "F.SilkS")
		)
		(fp_poly
			(pts
				(xy -2.549906 -3.050032) (xy -2.549906 3.050032) (xy 2.549906 3.050032) (xy 2.549906 -3.050032)
			)
			(stroke
				(width 0)
				(type default)
			)
			(fill no)
			(layer "F.CrtYd")
		)
		(fp_line
			(start 2.549906 -3.050032)
			(end 2.549906 3.050032)
			(stroke
				(width 0.1)
				(type default)
			)
			(layer "F.Fab")
		)
		(fp_line
			(start -2.549906 -3.050032)
			(end 2.549906 -3.050032)
			(stroke
				(width 0.1)
				(type default)
			)
			(layer "F.Fab")
		)
		(fp_line
			(start 2.549906 3.050032)
			(end -2.549906 3.050032)
			(stroke
				(width 0.1)
				(type default)
			)
			(layer "F.Fab")
		)
		(fp_line
			(start -2.549906 3.050032)
			(end -2.549906 -3.050032)
			(stroke
				(width 0.1)
				(type default)
			)
			(layer "F.Fab")
		)
		(fp_circle
			(center -3.057398 -2.678684)
			(end -3.057398 -2.551684)
			(stroke
				(width 0.254)
				(type default)
			)
			(fill no)
			(layer "F.Fab")
		)
		(pad "1" smd rect
			(at -2.39522 -2.279904 90)
			(size 0.7112 0.254)
			(layers "F.Cu" "F.Mask" "F.Paste")
			(net "PVCCIN_CPU1")
		)
		(pad "2" smd rect
			(at -2.39522 -1.83007 90)
			(size 0.7112 0.254)
			(layers "F.Cu" "F.Mask" "F.Paste")
			(net "GND")
		)
		(pad "3" smd rect
			(at -2.39522 -1.379982 90)
			(size 0.7112 0.254)
			(layers "F.Cu" "F.Mask" "F.Paste")
			(net "VR_PVCCIN_CPU1_PH1_VCIN")
		)
		(pad "4" smd rect
			(at -2.39522 -0.929894 90)
			(size 0.7112 0.254)
			(layers "F.Cu" "F.Mask" "F.Paste")
			(net "P5V_STBY")
		)
		(pad "5" smd rect
			(at -2.39522 -0.48006 90)
			(size 0.7112 0.254)
			(layers "F.Cu" "F.Mask" "F.Paste")
			(net "GND")
		)
		(pad "6" smd rect
			(at -2.39522 -0.029972 90)
			(size 0.7112 0.254)
			(layers "F.Cu" "F.Mask" "F.Paste")
			(net "TP_PVCCINC_CPU1_PH1_GL_0")
		)
		(pad "7" smd custom
			(at 0.016764 1.145032 90)
			(size 0.53975 0.53975)
			(layers "F.Cu" "F.Mask" "F.Paste")
			(net "GND")
			(options
				(clearance outline)
				(anchor circle)
			)
			(primitives
				(gr_poly
					(pts
						(xy -2.7051 1.0795) (xy -2.7051 -0.3683) (xy -0.9271 -0.3683) (xy -0.9271 -1.0795) (xy 2.7051 -1.0795)
						(xy 2.7051 1.0795)
					)
					(width 0)
					(fill yes)
				)
			)
		)
		(pad "10" smd rect
			(at -0.008382 2.874772 90)
			(size 4.3434 0.6096)
			(layers "F.Cu" "F.Mask" "F.Paste")
			(net "VR_PVCCIN_CPU1_PHASE1")
		)
		(pad "25" smd rect
			(at 1.548384 -1.283208 90)
			(size 2.3368 2.0066)
			(layers "F.Cu" "F.Mask" "F.Paste")
			(net "VR_FET_SW_P12V_STBY_PVCCIN_CPU1")
		)
		(pad "30" smd rect
			(at 2.050034 -2.895092 90)
			(size 0.254 0.7112)
			(layers "F.Cu" "F.Mask" "F.Paste")
			(net "VR_FET_SW_P12V_STBY_PVCCIN_CPU1")
		)
		(pad "31" smd rect
			(at 1.599946 -2.895092 90)
			(size 0.254 0.7112)
			(layers "F.Cu" "F.Mask" "F.Paste")
			(net "Net_356")
		)
		(pad "32" smd rect
			(at 1.150112 -2.895092 90)
			(size 0.254 0.7112)
			(layers "F.Cu" "F.Mask" "F.Paste")
			(net "VR_PVCCIN_CPU1_PH1_PHASE")
		)
		(pad "33" smd rect
			(at 0.700024 -2.895092 90)
			(size 0.254 0.7112)
			(layers "F.Cu" "F.Mask" "F.Paste")
			(net "VR_PVCCIN_CPU1_PH1_BOOT_R")
		)
		(pad "34" smd rect
			(at 0.249936 -2.895092 90)
			(size 0.254 0.7112)
			(layers "F.Cu" "F.Mask" "F.Paste")
			(net "VR_PVCCIN_CPU1_PWM1")
		)
		(pad "35" smd rect
			(at -0.199898 -2.895092 90)
			(size 0.254 0.7112)
			(layers "F.Cu" "F.Mask" "F.Paste")
			(net "P5V_STBY")
		)
		(pad "36" smd rect
			(at -0.649986 -2.895092 90)
			(size 0.254 0.7112)
			(layers "F.Cu" "F.Mask" "F.Paste")
			(net "A_TSENSE_PVCCIN_CPU1")
		)
		(pad "37" smd rect
			(at -1.100074 -2.895092 90)
			(size 0.254 0.7112)
			(layers "F.Cu" "F.Mask" "F.Paste")
			(net "VR_PVCCIN_CPU1_PH1_OCSET")
		)
		(pad "38" smd rect
			(at -1.549908 -2.895092 90)
			(size 0.254 0.7112)
			(layers "F.Cu" "F.Mask" "F.Paste")
			(net "ISENSE_PVCCIN_CPU1_PH1_IMON")
		)
		(pad "39" smd rect
			(at -1.999996 -2.895092 90)
			(size 0.254 0.7112)
			(layers "F.Cu" "F.Mask" "F.Paste")
			(net "VR_PVCCIN_CPU1_AIREF1")
		)
		(pad "40" smd rect
			(at -0.871728 -1.283208 90)
			(size 1.8034 2.0066)
			(layers "F.Cu" "F.Mask" "F.Paste")
			(net "GND")
		)
		(pad "41" smd rect
			(at -1.533906 0.247904 90)
			(size 0.508 0.3556)
			(layers "F.Cu" "F.Mask" "F.Paste")
			(net "TP_PVCCINC_CPU1_PH1_GL_1")
		)
	)
	(footprint ""
		(layer "F.Cu")
		(at 16.891 -80.4545)
		(property "Reference" "R1D25"
			(at 0 0 0)
			(layer "F.SilkS")
			(hide yes)
			(effects
				(font
					(size 1.27 1.27)
				)
			)
		)
		(property "Value" ""
			(at 0 0 0)
			(layer "F.Fab")
			(effects
				(font
					(size 1.27 1.27)
				)
			)
		)
		(duplicate_pad_numbers_are_jumpers no)
		(fp_rect
			(start 0.2794 0.9906)
			(end -0.2794 -0.1016)
			(stroke
				(width 0)
				(type default)
			)
			(fill no)
			(layer "F.CrtYd")
		)
		(fp_line
			(start -0.2794 -0.1016)
			(end -0.2794 0.9906)
			(stroke
				(width 0.1)
				(type default)
			)
			(layer "F.Fab")
		)
		(fp_line
			(start -0.2794 0.9906)
			(end 0.2794 0.9906)
			(stroke
				(width 0.1)
				(type default)
			)
			(layer "F.Fab")
		)
		(fp_line
			(start 0.2794 -0.1016)
			(end -0.2794 -0.1016)
			(stroke
				(width 0.1)
				(type default)
			)
			(layer "F.Fab")
		)
		(fp_line
			(start 0.2794 0.9906)
			(end 0.2794 -0.1016)
			(stroke
				(width 0.1)
				(type default)
			)
			(layer "F.Fab")
		)
		(pad "1" smd rect
			(at 0 0)
			(size 0.508 0.508)
			(layers "F.Cu" "F.Mask" "F.Paste")
			(net "SMB_BMC_PMBUS_STBY_LVC3_SDA")
		)
		(pad "2" smd rect
			(at 0 0.889)
			(size 0.508 0.508)
			(layers "F.Cu" "F.Mask" "F.Paste")
			(net "SMB_3V3SB_HSC_SDA_R")
		)
		(zone
			(layer "F.Cu")
			(hatch none 0.5)
			(connect_pads
				(clearance 0)
			)
			(min_thickness 0.25)
			(keepout
				(tracks allowed)
				(vias not_allowed)
				(pads allowed)
				(copperpour not_allowed)
				(footprints allowed)
			)
			(placement
				(enabled no)
				(sheetname "")
			)
			(fill
				(thermal_gap 0.5)
				(thermal_bridge_width 0.5)
				(island_removal_mode 0)
			)
			(polygon
				(pts
					(xy 17.145 -79.8195) (xy 17.145 -80.2005) (xy 16.637 -80.2005) (xy 16.637 -79.8195)
				)
			)
		)
		(zone
			(layer "F.Cu")
			(hatch none 0.5)
			(connect_pads
				(clearance 0)
			)
			(min_thickness 0.25)
			(keepout
				(tracks not_allowed)
				(vias allowed)
				(pads allowed)
				(copperpour not_allowed)
				(footprints allowed)
			)
			(placement
				(enabled no)
				(sheetname "")
			)
			(fill
				(thermal_gap 0.5)
				(thermal_bridge_width 0.5)
				(island_removal_mode 0)
			)
			(polygon
				(pts
					(xy 17.145 -79.8195) (xy 17.145 -80.2005) (xy 16.637 -80.2005) (xy 16.637 -79.8195)
				)
			)
		)
	)
)
